# T6G (Grand Teton) — schematic parts with pin connectivity, parts 170–343 of 8303; source: Cadence DE-HDL packaged netlist (pstxprt.dat, pstxnet.dat, pstchip.dat)

C169  Q_CAP  10UF 25V 10% X6S  pkg C0805  page 96 : 1 = P12V_MEM_CPU0 ; 2 = GND
C170  Q_CAP  10UF 25V 10% X6S  pkg C0805  page 97 : 1 = P12V_MEM_CPU0 ; 2 = GND
C171  Q_CAP  10UF 25V 10% X6S  pkg C0805  page 97 : 1 = P12V_MEM_CPU0 ; 2 = GND
C172  Q_CAP  0.1UF 25V 10% X7R  pkg 0402  page 107 : 1 = P3V3_AUX ; 2 = GND
C173  Q_CAP  10UF 25V 10% X6S  pkg C0805  page 98 : 1 = P12V_MEM_CPU1 ; 2 = GND
C174  Q_CAP  10UF 25V 10% X6S  pkg C0805  page 98 : 1 = P12V_MEM_CPU1 ; 2 = GND
C175  Q_CAP  10UF 25V 10% X6S  pkg C0805  page 99 : 1 = P12V_MEM_CPU1 ; 2 = GND
C176  Q_CAP  0.1UF 25V 10% X7R  pkg 0402  page 108 : 1 = P3V3_AUX ; 2 = GND
C177  Q_CAP  10UF 25V 10% X6S  pkg C0805  page 99 : 1 = P12V_MEM_CPU1 ; 2 = GND
C178  Q_CAP  10UF 25V 10% X6S  pkg C0805  page 100 : 1 = P12V_MEM_CPU1 ; 2 = GND
C179  Q_CAP  10UF 25V 10% X6S  pkg C0805  page 100 : 1 = P12V_MEM_CPU1 ; 2 = GND
C180  Q_CAP  0.1UF 25V 10% X7R  pkg 0402  page 109 : 1 = P3V3_AUX ; 2 = GND
C181  Q_CAP  10UF 25V 10% X6S  pkg C0805  page 101 : 1 = P12V_MEM_CPU1 ; 2 = GND
C182  Q_CAP  10UF 25V 10% X6S  pkg C0805  page 101 : 1 = P12V_MEM_CPU1 ; 2 = GND
C183  Q_CAP  10UF 25V 10% X6S  pkg C0805  page 102 : 1 = P12V_MEM_CPU1 ; 2 = GND
C184  Q_CAP  0.1UF 10V 10% X7S  pkg C0201  page 323 : 1 = P0V9_CPU1_RT0_2A ; 2 = GND
C185  Q_CAP  1UF 4V 20% X6S  pkg 0201  page 323 : 1 = P0V9_CPU1_RT_2D ; 2 = GND
C186  Q_CAP  1UF 4V 20% X6S  pkg 0201  page 323 : 1 = P0V9_CPU1_RT0_2A ; 2 = GND
C187  Q_CAP  1UF 4V 20% X6S  pkg 0201  page 323 : 1 = P0V9_CPU1_RT0_2A_2D ; 2 = GND
C188  Q_CAP  1UF 4V 20% X6S  pkg 0201  page 323 : 1 = P0V9_CPU1_RT0_2A ; 2 = GND
C189  Q_CAP  0.1UF 10V 10% X7S  pkg C0201  page 323 : 1 = P0V9_CPU1_RT_2D ; 2 = GND
C190  Q_CAP  1UF 4V 20% X6S  pkg 0201  page 323 : 1 = P0V9_CPU1_RT0_2A ; 2 = GND
C191  Q_CAP  0.1UF 10V 10% X7S  pkg C0201  page 323 : 1 = P0V9_CPU1_RT0_2A_2D ; 2 = GND
C192  Q_CAP  0.1UF 10V 10% X7S  pkg C0201  page 323 : 1 = P0V9_CPU1_RT0_2A ; 2 = GND
C193  Q_CAP  100NF 50V 10% X7R  pkg C0402  page 187 : 1 = P1V5_BAT_IN ; 2 = GND
C194  Q_CAP  0.1UF 16V 10% X7R  pkg C0402  page 171 : 1 = P3V3_AUX ; 2 = GND
C195  Q_CAP  4.7UF 6.3V 20% X6S  pkg 0402  page 334 : 1 = P1V8_CPU1_RT1_1A ; 2 = GND
C196  Q_CAP  1000PF 50V 5% EMPTY  pkg 0402  page 207 : 1 = PWRGD_PVDD11_S3_P0_R ; 2 = GND
C197  Q_CAP  1000PF 50V 5% X7R  pkg 0402  page 207 : 1 = PVDD11_S3_P0_EN_R ; 2 = GND
C198  Q_CAP  0.1UF 10V 10% X7S  pkg C0201  page 323 : 1 = P0V9_CPU1_RT0_2A_2D ; 2 = GND
C199  Q_CAP  10UF 6.3V 20% X6S  pkg C0402  page 334 : 1 = P1V8_CPU1_RT1_1A ; 2 = GND
C200  Q_CAP  4.7UF 6.3V 20% X6S  pkg 0402  page 334 : 1 = P1V8_CPU1_RT_1D ; 2 = GND
C201  Q_CAP  1UF 4V 20% X6S  pkg 0201  page 323 : 1 = P0V9_CPU1_RT0_2A_2D ; 2 = GND
C202  Q_CAP  1UF 4V 20% X6S  pkg 0201  page 334 : 1 = P1V8_CPU1_RT1_1A ; 2 = GND
C203  Q_CAP  1UF 4V 20% X6S  pkg 0201  page 334 : 1 = P1V8_CPU1_RT1_1A_1D ; 2 = GND
C204  Q_CAP  1UF 4V 20% X6S  pkg 0201  page 334 : 1 = P1V8_CPU1_RT1_1A ; 2 = GND
C205  Q_CAP  0.1UF 10V 10% X7S  pkg C0201  page 334 : 1 = P1V8_CPU1_RT1_1A ; 2 = GND
C206  Q_CAP  0.1UF 10V 10% X7S  pkg C0201  page 334 : 1 = P1V8_CPU1_RT1_1A_1D ; 2 = GND
C207  Q_CAP  0.001UF 50V 10% EMPTY  pkg C0402  page 27 : 1 = JTAG_CPU0_TDO ; 2 = GND
C208  Q_CAP  0.001UF 50V 10% EMPTY  pkg C0402  page 27 : 1 = JTAG_CPU0_TDI ; 2 = GND
C209  Q_CAP  0.001UF 50V 10% EMPTY  pkg C0402  page 27 : 1 = JTAG_CPU0_TRST_N ; 2 = GND
C210  Q_CAP  0.001UF 50V 10% EMPTY  pkg C0402  page 27 : 1 = JTAG_CPU0_TCK ; 2 = GND
C211  Q_CAP  0.001UF 50V 10% EMPTY  pkg C0402  page 27 : 1 = JTAG_CPU0_TMS ; 2 = GND
C212  Q_CAP  0.001UF 50V 10% EMPTY  pkg C0402  page 27 : 1 = JTAG_CPU0_DBREQ_N ; 2 = GND
C213  Q_CAP  3.9P 50V 0.1P NPO  pkg C0402  page 28 : 1 = XTAL_CPU0_X48M_X1 ; 2 = GND
C214  Q_CAP  3.9P 50V 0.1P NPO  pkg C0402  page 28 : 1 = XTAL_CPU0_X48M_X2_R ; 2 = GND
C215  Q_CAP  8.2PF 50V 0.1P NP0  pkg C0402  page 28 : 1 = XTAL_CPU0_X32K_X1 ; 2 = GND
C216  Q_CAP  8.2PF 50V 0.1P NP0  pkg C0402  page 28 : 1 = XTAL_CPU0_X32K_X2 ; 2 = GND
C217  Q_CAP  0.1UF 10V 10% X7S  pkg C0201  page 334 : 1 = P1V8_CPU1_RT1_1A ; 2 = GND
C218  Q_CAP  0.1UF 25V 10% X7R  pkg 0402  page 166 : 1 = P1V8_AUX ; 2 = GND
C219  Q_CAP  0.1UF 25V 10% X7R  pkg 0402  page 166 : 1 = P1V8_AUX ; 2 = GND
C220  Q_CAP  100UF 4V 20% X6S  pkg C0805  page 323 : 1 = P0V9_CPU1_RT0_2A ; 2 = GND
C221  Q_CAP  4.7UF 6.3V 20% X6S  pkg 0402  page 323 : 1 = P0V9_CPU1_RT0_2A ; 2 = GND
C222  Q_CAP  1UF 4V 20% X6S  pkg 0201  page 323 : 1 = P0V9_CPU1_RT0_2A ; 2 = GND
C223  Q_CAP  0.1UF 25V 10% X7R  pkg 0402  page 78 : 1 = P1V8_AUX ; 2 = GND
C224  Q_CAP  0.1UF 25V 10% X7R  pkg 0402  page 78 : 1 = P1V8_AUX ; 2 = GND
C225  Q_CAP  100UF 4V 20% X6S  pkg C0805  page 323 : 1 = P0V9_CPU1_RT0_2A ; 2 = GND
C226  Q_CAP  0.1UF 25V 10% X7R  pkg 0402  page 34 : 1 = PVDD18_S5_P0 ; 2 = GND
C227  Q_CAP  4.7UF 6.3V 20% X6S  pkg 0402  page 323 : 1 = P0V9_CPU1_RT0_2A ; 2 = GND
C228  Q_CAP  0.1UF 10V 10% X7S  pkg C0201  page 323 : 1 = P0V9_CPU1_RT0_2A ; 2 = GND
C229  Q_CAP  100UF 4V 20% X6S  pkg C0805  page 323 : 1 = P0V9_CPU1_RT_2D ; 2 = GND
C230  Q_CAP  0.001UF 50V 10% EMPTY  pkg C0402  page 54 : 1 = JTAG_CPU1_TDO ; 2 = GND
C231  Q_CAP  0.001UF 50V 10% EMPTY  pkg C0402  page 54 : 1 = JTAG_CPU1_TDI ; 2 = GND
C232  Q_CAP  0.001UF 50V 10% EMPTY  pkg C0402  page 54 : 1 = JTAG_CPU1_TRST_N ; 2 = GND
C233  Q_CAP  0.001UF 50V 10% EMPTY  pkg C0402  page 54 : 1 = JTAG_CPU1_TCK ; 2 = GND
C234  Q_CAP  0.001UF 50V 10% EMPTY  pkg C0402  page 54 : 1 = JTAG_CPU1_TMS ; 2 = GND
C235  Q_CAP  0.001UF 50V 10% EMPTY  pkg C0402  page 54 : 1 = JTAG_CPU1_DBREQ_N ; 2 = GND
C236  Q_CAP  2.7PF 50V 0.1PF NPO  pkg C0402  page 55 : 1 = XTAL_CPU1_X48M_X1 ; 2 = GND
C237  Q_CAP  2.7PF 50V 0.1PF NPO  pkg C0402  page 55 : 1 = XTAL_CPU1_X48M_X2_R ; 2 = GND
C238  Q_CAP  10PF 50V 1% NPO  pkg 0402  page 55 : 1 = XTAL_CPU1_R_X32K_X1 ; 2 = GND
C239  Q_CAP  10PF 50V 1% NPO  pkg 0402  page 55 : 1 = XTAL_CPU1_R_X32K_X2 ; 2 = GND
C240  Q_CAP  100UF 4V 20% X6S  pkg C0805  page 323 : 1 = P0V9_CPU1_RT0_2A ; 2 = GND
C241  Q_CAP  4.7UF 6.3V 20% X6S  pkg 0402  page 323 : 1 = P0V9_CPU1_RT0_2A ; 2 = GND
C242  Q_CAP  1000PF 50V 5% X7R  pkg 0402  page 210 : 1 = PVDDCR_SOC_P1_EN_RC ; 2 = GND
C243  Q_CAP  1UF 4V 20% X6S  pkg 0201  page 323 : 1 = P0V9_CPU1_RT0_2A ; 2 = GND
C244  Q_CAP  22UF 4V 20% X6S  pkg C0402  page 323 : 1 = P0V9_CPU1_RT_2D ; 2 = GND
C245  Q_CAP  22UF 4V 20% X6S  pkg C0402  page 69 : 1 = PVDDCR_CPU0_P0 ; 2 = GND
C246  Q_CAP  22UF 4V 20% X6S  pkg C0402  page 69 : 1 = PVDDCR_CPU0_P0 ; 2 = GND
C247  Q_CAP  100UF 4V 20% X6S  pkg C0805  page 323 : 1 = P0V9_CPU1_RT0_2A ; 2 = GND
C248  Q_CAP  1000PF 50V 5% EMPTY  pkg 0402  page 210 : 1 = PWRGD_PVDDCR_CPU0_P1_R ; 2 = GND
C249  Q_CAP  1000PF 50V 5% X7R  pkg 0402  page 210 : 1 = PVDDCR_CPU0_P1_EN_R ; 2 = GND
C250  Q_CAP  10UF 6.3V 20% X6S  pkg C0402  page 323 : 1 = P0V9_CPU1_RT0_2A ; 2 = GND
C251  Q_CAP  22UF 4V 20% X6S  pkg C0402  page 69 : 1 = PVDDCR_CPU0_P0 ; 2 = GND
C252  Q_CAP  22UF 4V 20% X6S  pkg C0402  page 69 : 1 = PVDDCR_CPU0_P0 ; 2 = GND
C253  Q_CAP  0.1UF 10V 10% X7S  pkg C0201  page 323 : 1 = P0V9_CPU1_RT0_2A ; 2 = GND
C254  Q_CAP  10UF 6.3V 20% X6S  pkg C0402  page 323 : 1 = P0V9_CPU1_RT0_2A ; 2 = GND
C255  Q_CAP  22UF 4V 20% X6S  pkg C0402  page 323 : 1 = P0V9_CPU1_RT0_2A ; 2 = GND
C256  Q_CAP  4.7UF 6.3V 20% X6S  pkg 0402  page 323 : 1 = P0V9_CPU1_RT_2D ; 2 = GND
C257  Q_CAP  1UF 4V 20% X6S  pkg 0201  page 323 : 1 = P0V9_CPU1_RT0_2A ; 2 = GND
C258  Q_CAP  4.7UF 6.3V 20% X6S  pkg 0402  page 323 : 1 = P0V9_CPU1_RT0_2A ; 2 = GND
C259  Q_CAP  22UF 4V 20% X6S  pkg C0402  page 323 : 1 = P0V9_CPU1_RT0_2A ; 2 = GND
C260  Q_CAP  0.1UF 10V 10% X7S  pkg C0201  page 323 : 1 = P0V9_CPU1_RT0_2A ; 2 = GND
C261  Q_CAP  10UF 6.3V 20% X6S  pkg C0402  page 323 : 1 = P0V9_CPU1_RT_2D ; 2 = GND
C262  Q_CAP  22UF 4V 20% X6S  pkg C0402  page 323 : 1 = P0V9_CPU1_RT0_2A ; 2 = GND
C263  Q_CAP  22UF 4V 20% X6S  pkg C0402  page 69 : 1 = PVDDCR_CPU0_P0 ; 2 = GND
C264  Q_CAP  0.1UF 10V 10% X7S  pkg C0201  page 323 : 1 = P0V9_CPU1_RT0_2A ; 2 = GND
C265  Q_CAP  1UF 4V 20% X6S  pkg 0201  page 323 : 1 = P0V9_CPU1_RT0_2A ; 2 = GND
C266  Q_CAP  0.1UF 10V 10% X7S  pkg C0201  page 323 : 1 = P0V9_CPU1_RT_2D ; 2 = GND
C267  Q_CAP  22UF 4V 20% X6S  pkg C0402  page 69 : 1 = PVDDCR_CPU0_P0 ; 2 = GND
C268  Q_CAP  22UF 4V 20% X6S  pkg C0402  page 69 : 1 = PVDDCR_CPU0_P0 ; 2 = GND
C269  Q_CAP  10UF 6.3V 20% X6S  pkg C0402  page 323 : 1 = P0V9_CPU1_RT0_2A ; 2 = GND
C270  Q_CAP  22UF 4V 20% X6S  pkg C0402  page 69 : 1 = PVDDCR_CPU0_P0 ; 2 = GND
C271  Q_CAP  22UF 4V 20% X6S  pkg C0402  page 69 : 1 = PVDDCR_CPU0_P0 ; 2 = GND
C272  Q_CAP  22UF 4V 20% X6S  pkg C0402  page 69 : 1 = PVDDCR_CPU0_P0 ; 2 = GND
C273  Q_CAP  22UF 4V 20% X6S  pkg C0402  page 69 : 1 = PVDDCR_CPU0_P0 ; 2 = GND
C274  Q_CAP  22UF 4V 20% X6S  pkg C0402  page 69 : 1 = PVDDCR_CPU0_P0 ; 2 = GND
C275  Q_CAP  22UF 4V 20% X6S  pkg C0402  page 69 : 1 = PVDDCR_CPU0_P0 ; 2 = GND
C276  Q_CAP  22UF 4V 20% X6S  pkg C0402  page 69 : 1 = PVDDCR_CPU0_P0 ; 2 = GND
C277  Q_CAP  22UF 4V 20% X6S  pkg C0402  page 69 : 1 = PVDDCR_CPU0_P0 ; 2 = GND
C278  Q_CAP  22UF 4V 20% X6S  pkg C0402  page 69 : 1 = PVDDCR_CPU0_P0 ; 2 = GND
C279  Q_CAP  22UF 4V 20% X6S  pkg C0402  page 69 : 1 = PVDDCR_CPU0_P0 ; 2 = GND
C280  Q_CAP  1UF 4V 20% X6S  pkg 0201  page 323 : 1 = P0V9_CPU1_RT0_2A ; 2 = GND
C281  Q_CAP  0.1UF 10V 10% X7S  pkg C0201  page 323 : 1 = P0V9_CPU1_RT0_2A ; 2 = GND
C282  Q_CAP  0.1UF 10V 10% X7S  pkg C0201  page 323 : 1 = P0V9_CPU1_RT0_2A ; 2 = GND
C283  Q_CAP  0.1UF 10V 10% X7S  pkg C0201  page 323 : 1 = P0V9_CPU1_RT0_2A ; 2 = GND
C284  Q_CAP  22UF 4V 20% X6S  pkg C0402  page 323 : 1 = P0V9_CPU1_RT0_2A ; 2 = GND
C285  Q_CAP  1UF 4V 20% X6S  pkg 0201  page 323 : 1 = P0V9_CPU1_RT0_2A ; 2 = GND
C286  Q_CAP  10UF 6.3V 20% X6S  pkg C0402  page 323 : 1 = P0V9_CPU1_RT0_2A ; 2 = GND
C287  Q_CAP  0.1UF 10V 10% X7S  pkg C0201  page 334 : 1 = P1V8_CPU1_RT1_1A ; 2 = GND
C288  Q_CAP  0.1UF 10V 10% X7S  pkg C0201  page 334 : 1 = P1V8_CPU1_RT1_1A ; 2 = GND
C289  Q_CAP  1UF 4V 20% X6S  pkg 0201  page 334 : 1 = P0V9_CPU1_RT1_2A ; 2 = GND
C290  Q_CAP  0.1UF 10V 10% X7S  pkg C0201  page 334 : 1 = P0V9_CPU1_RT_2D ; 2 = GND
C291  Q_CAP  0.1UF 10V 10% X7S  pkg C0201  page 334 : 1 = P0V9_CPU1_RT1_2A ; 2 = GND
C292  Q_CAP  0.1UF 10V 10% X7S  pkg C0201  page 334 : 1 = P0V9_CPU1_RT_2D ; 2 = GND
C293  Q_CAP  1UF 4V 20% X6S  pkg 0201  page 334 : 1 = P0V9_CPU1_RT1_2A ; 2 = GND
C294  Q_CAP  1UF 4V 20% X6S  pkg 0201  page 334 : 1 = P0V9_CPU1_RT1_2A ; 2 = GND
C295  Q_CAP  10PF 50V 5% EMPTY  pkg 0402  page 210 : 1 = SVID_PVDDCR_CPU0_P1_SVTO ; 2 = GND
C296  Q_CAP  10PF 50V 5% EMPTY  pkg 0402  page 210 : 1 = SVID_PVDDCR_CPU0_P1_SVD_R ; 2 = GND
C297  Q_CAP  10PF 50V 5% EMPTY  pkg 0402  page 210 : 1 = SVID_PVDDCR_CPU0_P1_SVC_R ; 2 = GND
C298  Q_CAP  10PF 50V 5% EMPTY  pkg 0402  page 193 : 1 = SVID_PVDDCR_CPU0_P0_SVTO ; 2 = GND
C299  Q_CAP  10PF 50V 5% EMPTY  pkg 0402  page 193 : 1 = SVID_PVDDCR_CPU0_P0_SVD_R ; 2 = GND
C300  Q_CAP  0.1UF 10V 10% X7S  pkg C0201  page 334 : 1 = P0V9_CPU1_RT_2D ; 2 = GND
C301  Q_CAP  1UF 4V 20% X6S  pkg 0201  page 334 : 1 = P0V9_CPU1_RT1_2A ; 2 = GND
C302  Q_CAP  10PF 50V 5% EMPTY  pkg 0402  page 193 : 1 = SVID_PVDDCR_CPU0_P0_SVC_R ; 2 = GND
C303  Q_CAP  10PF 50V 5% EMPTY  pkg 0402  page 200 : 1 = SVID_PVDDCR_CPU1_P0_SVTO ; 2 = GND
C304  Q_CAP  10PF 50V 5% EMPTY  pkg 0402  page 200 : 1 = SVID_PVDDCR_CPU1_P0_SVD_R ; 2 = GND
C305  Q_CAP  10PF 50V 5% EMPTY  pkg 0402  page 200 : 1 = SVID_PVDDCR_CPU1_P0_SVC_R ; 2 = GND
C306  Q_CAP  1UF 4V 20% X6S  pkg 0201  page 334 : 1 = P0V9_CPU1_RT1_2A_2D ; 2 = GND
C307  Q_CAP  1UF 4V 20% X6S  pkg 0201  page 334 : 1 = P0V9_CPU1_RT1_2A ; 2 = GND
C308  Q_CAP  10PF 50V 5% EMPTY  pkg 0402  page 217 : 1 = SVID_PVDDCR_CPU1_P1_SVTO ; 2 = GND
C309  Q_CAP  10PF 50V 5% EMPTY  pkg 0402  page 217 : 1 = SVID_PVDDCR_CPU1_P1_SVD_R ; 2 = GND
C310  Q_CAP  10PF 50V 5% EMPTY  pkg 0402  page 217 : 1 = SVID_PVDDCR_CPU1_P1_SVC_R ; 2 = GND
C311  Q_CAP  0.1UF 10V 10% X7S  pkg C0201  page 334 : 1 = P0V9_CPU1_RT_2D ; 2 = GND
C312  Q_CAP  0.1UF 10V 10% X7S  pkg C0201  page 334 : 1 = P0V9_CPU1_RT1_2A ; 2 = GND
C313  Q_CAP  0.1UF 10V 10% X7S  pkg C0201  page 334 : 1 = P0V9_CPU1_RT1_2A_2D ; 2 = GND
C314  Q_CAP  1UF 4V 20% X6S  pkg 0201  page 334 : 1 = P0V9_CPU1_RT1_2A ; 2 = GND
C315  Q_CAP  1UF 4V 20% X6S  pkg 0201  page 334 : 1 = P0V9_CPU1_RT1_2A_2D ; 2 = GND
C316  Q_CAP  0.1UF 10V 10% X7S  pkg C0201  page 334 : 1 = P0V9_CPU1_RT1_2A_2D ; 2 = GND
C317  Q_CAP  100UF 4V 20% X6S  pkg C0805  page 334 : 1 = P0V9_CPU1_RT1_2A ; 2 = GND
C318  Q_CAP  22UF 4V 20% X6S  pkg C0402  page 334 : 1 = P0V9_CPU1_RT1_2A ; 2 = GND
C319  Q_CAP  0.1UF 10V 10% X7S  pkg C0201  page 334 : 1 = P0V9_CPU1_RT1_2A ; 2 = GND
C320  Q_CAP  100UF 4V 20% X6S  pkg C0805  page 334 : 1 = P0V9_CPU1_RT1_2A ; 2 = GND
C321  Q_CAP  10UF 6.3V 20% X6S  pkg C0402  page 334 : 1 = P0V9_CPU1_RT1_2A ; 2 = GND
C322  Q_CAP  0.1UF 10V 10% X7S  pkg C0201  page 334 : 1 = P0V9_CPU1_RT1_2A ; 2 = GND
C323  Q_CAP  100UF 4V 20% X6S  pkg C0805  page 334 : 1 = P0V9_CPU1_RT_2D ; 2 = GND
C324  Q_CAP  100UF 4V 20% X6S  pkg C0805  page 334 : 1 = P0V9_CPU1_RT1_2A ; 2 = GND
C325  Q_CAP  4.7UF 6.3V 20% X6S  pkg 0402  page 334 : 1 = P0V9_CPU1_RT1_2A ; 2 = GND
C326  Q_CAP  1UF 4V 20% X6S  pkg 0201  page 334 : 1 = P0V9_CPU1_RT1_2A ; 2 = GND
C327  Q_CAP  22UF 4V 20% X6S  pkg C0402  page 334 : 1 = P0V9_CPU1_RT_2D ; 2 = GND
C328  Q_CAP  100UF 4V 20% X6S  pkg C0805  page 334 : 1 = P0V9_CPU1_RT1_2A ; 2 = GND
C329  Q_CAP  22UF 4V 20% X6S  pkg C0402  page 334 : 1 = P0V9_CPU1_RT1_2A ; 2 = GND
C330  Q_CAP  1UF 4V 20% X6S  pkg 0201  page 334 : 1 = P0V9_CPU1_RT1_2A ; 2 = GND
C331  Q_CAP  4.7UF 6.3V 20% X6S  pkg 0402  page 334 : 1 = P0V9_CPU1_RT1_2A ; 2 = GND
C332  Q_CAP  10UF 6.3V 20% X6S  pkg C0402  page 334 : 1 = P0V9_CPU1_RT1_2A ; 2 = GND
C333  Q_CAP  10UF 6.3V 20% X6S  pkg C0402  page 334 : 1 = P0V9_CPU1_RT_2D ; 2 = GND
C334  Q_CAP  0.1UF 10V 10% X7S  pkg C0201  page 334 : 1 = P0V9_CPU1_RT1_2A ; 2 = GND
C335  Q_CAP  22UF 4V 20% X6S  pkg C0402  page 334 : 1 = P0V9_CPU1_RT1_2A ; 2 = GND
C336  Q_CAP  4.7UF 6.3V 20% X6S  pkg 0402  page 334 : 1 = P0V9_CPU1_RT1_2A ; 2 = GND
C337  Q_CAP  1UF 4V 20% X6S  pkg 0201  page 334 : 1 = P0V9_CPU1_RT1_2A ; 2 = GND
C338  Q_CAP  4.7UF 6.3V 20% X6S  pkg 0402  page 334 : 1 = P0V9_CPU1_RT_2D ; 2 = GND
C339  Q_CAP  10UF 6.3V 20% X6S  pkg C0402  page 334 : 1 = P0V9_CPU1_RT1_2A ; 2 = GND
C340  Q_CAP  0.1UF 10V 10% X7S  pkg C0201  page 334 : 1 = P0V9_CPU1_RT1_2A ; 2 = GND
C341  Q_CAP  0.1UF 10V 10% X7S  pkg C0201  page 334 : 1 = P0V9_CPU1_RT1_2A ; 2 = GND
C342  Q_CAP  1UF 4V 20% X6S  pkg 0201  page 334 : 1 = P0V9_CPU1_RT_2D ; 2 = GND
